(kicad_pcb
	(version 20241229)
	(generator "pcbnew")
	(generator_version "9.0")
	(general
		(thickness 1.599998)
		(legacy_teardrops no)
	)
	(paper "A4")
	(title_block
		(title "Artix - Datacenter Secure Control Module (DC-SCM)")
		(date "2024-11-06")
		(rev "1.1.3")
		(comment 9 "footprints 393-398 of 544")
	)
	(layers
		(0 "F.Cu" signal)
		(4 "In1.Cu" signal)
		(6 "In2.Cu" signal)
		(8 "In3.Cu" signal)
		(10 "In4.Cu" signal)
		(12 "In5.Cu" signal)
		(14 "In6.Cu" signal)
		(2 "B.Cu" signal)
		(9 "F.Adhes" user "F.Adhesive")
		(11 "B.Adhes" user "B.Adhesive")
		(13 "F.Paste" user)
		(15 "B.Paste" user)
		(5 "F.SilkS" user "F.Silkscreen")
		(7 "B.SilkS" user "B.Silkscreen")
		(1 "F.Mask" user)
		(3 "B.Mask" user)
		(17 "Dwgs.User" user "User.Drawings")
		(19 "Cmts.User" user "User.Comments")
		(21 "Eco1.User" user "User.Eco1")
		(23 "Eco2.User" user "User.Eco2")
		(25 "Edge.Cuts" user)
		(27 "Margin" user)
		(31 "F.CrtYd" user "F.Courtyard")
		(29 "B.CrtYd" user "B.Courtyard")
		(35 "F.Fab" user)
		(33 "B.Fab" user)
	)
	(footprint "antmicro-footprints:FB_0603_1608Metric"
		(layer "B.Cu")
		(at 108.019 93.327)
		(property "Reference" "FB5"
			(at 3.481 -2.527 0)
			(layer "B.SilkS")
			(effects
				(font
					(size 0.7 0.7)
					(thickness 0.15)
				)
				(justify right bottom mirror)
			)
		)
		(property "Value" "FB_120Z_2A_Murata-BLM18PG_0603"
			(at 0 -1.7 0)
			(layer "B.Fab")
			(effects
				(font
					(size 0.7 0.7)
					(thickness 0.15)
				)
				(justify right bottom mirror)
			)
		)
		(property "Datasheet" "https://www.murata.com/en-us/products/productdata/8796738650142/ENFA0003.pdf"
			(at 0 0 0)
			(layer "F.Fab")
			(hide yes)
			(effects
				(font
					(size 1.27 1.27)
					(thickness 0.15)
				)
			)
		)
		(property "Description" "Ferrite Bead, 0603 [1608 Metric], 120 ohm, 2 A, BLM18P, 0.05 ohm, ± 25%, DC power line"
			(at 0 0 0)
			(layer "F.Fab")
			(hide yes)
			(effects
				(font
					(size 1.27 1.27)
					(thickness 0.15)
				)
			)
		)
		(property "Author" "Antmicro"
			(at 0 0 0)
			(layer "B.Fab")
			(hide yes)
			(effects
				(font
					(size 1 1)
					(thickness 0.15)
				)
				(justify mirror)
			)
		)
		(property "Current" ""
			(at 0 0 0)
			(layer "B.Fab")
			(hide yes)
			(effects
				(font
					(size 1 1)
					(thickness 0.15)
				)
				(justify mirror)
			)
		)
		(property "License" "Apache-2.0"
			(at 0 0 0)
			(layer "B.Fab")
			(hide yes)
			(effects
				(font
					(size 1 1)
					(thickness 0.15)
				)
				(justify mirror)
			)
		)
		(property "MPN" "BLM18PG121SN1D"
			(at 0 0 0)
			(layer "B.Fab")
			(hide yes)
			(effects
				(font
					(size 1 1)
					(thickness 0.15)
				)
				(justify mirror)
			)
		)
		(property "Manufacturer" "Murata"
			(at 0 0 0)
			(layer "B.Fab")
			(hide yes)
			(effects
				(font
					(size 1 1)
					(thickness 0.15)
				)
				(justify mirror)
			)
		)
		(property "Val" "120Z/2A"
			(at 0 0 0)
			(layer "B.Fab")
			(hide yes)
			(effects
				(font
					(size 1 1)
					(thickness 0.15)
				)
				(justify mirror)
			)
		)
		(sheetname "/Ethernet/")
		(sheetfile "ethernet.kicad_sch")
		(attr smd)
		(fp_line
			(start -0.15 -0.4)
			(end 0.15 -0.4)
			(stroke
				(width 0.15)
				(type solid)
			)
			(layer "B.SilkS")
		)
		(fp_line
			(start -0.15 0.4)
			(end 0.15 0.4)
			(stroke
				(width 0.15)
				(type solid)
			)
			(layer "B.SilkS")
		)
		(fp_rect
			(start -1.25 0.65)
			(end 1.25 -0.65)
			(stroke
				(width 0.05)
				(type solid)
			)
			(fill no)
			(layer "B.CrtYd")
		)
		(fp_line
			(start -0.803 -0.406)
			(end -0.803 0.408)
			(stroke
				(width 0.15)
				(type solid)
			)
			(layer "B.Fab")
		)
		(fp_line
			(start 0.8 -0.406)
			(end -0.803 -0.406)
			(stroke
				(width 0.15)
				(type solid)
			)
			(layer "B.Fab")
		)
		(fp_line
			(start 0.8 0.408)
			(end -0.803 0.408)
			(stroke
				(width 0.15)
				(type solid)
			)
			(layer "B.Fab")
		)
		(fp_line
			(start 0.8 0.408)
			(end 0.8 -0.406)
			(stroke
				(width 0.15)
				(type solid)
			)
			(layer "B.Fab")
		)
		(pad "1" smd roundrect
			(at -0.7 0)
			(size 0.8 1)
			(layers "B.Cu" "B.Mask" "B.Paste")
			(roundrect_rratio 0.2)
			(net 404 "/Ethernet/AVDDL_PLL")
			(pintype "passive")
		)
		(pad "2" smd roundrect
			(at 0.7 0)
			(size 0.8 1)
			(layers "B.Cu" "B.Mask" "B.Paste")
			(roundrect_rratio 0.2)
			(net 339 "VCC1V2")
			(pintype "passive")
		)
	)
	(footprint "antmicro-footprints:C_0402_1005Metric"
		(layer "B.Cu")
		(at 107.725 99.35 180)
		(descr "Capacitor SMD 0402")
		(tags "capacitor SMD 0402")
		(property "Reference" "C196"
			(at -5.875 2.8 0)
			(layer "B.SilkS")
			(effects
				(font
					(size 0.7 0.7)
					(thickness 0.15)
				)
				(justify left bottom mirror)
			)
		)
		(property "Value" "C_4u7_0402"
			(at 0 -1.4 0)
			(layer "B.Fab")
			(effects
				(font
					(size 0.7 0.7)
					(thickness 0.15)
				)
				(justify left bottom mirror)
			)
		)
		(property "Datasheet" "https://www.murata.com/products/productdetail?partno=GRM155R61A475MEAA%23"
			(at 0 0 180)
			(layer "F.Fab")
			(hide yes)
			(effects
				(font
					(size 1.27 1.27)
					(thickness 0.15)
				)
			)
		)
		(property "Description" "SMD Multilayer Ceramic Capacitor, 4.7 µF, 10 V, 0402 [1005 Metric], ± 20%, X5R, GRM Series"
			(at 0 0 180)
			(layer "F.Fab")
			(hide yes)
			(effects
				(font
					(size 1.27 1.27)
					(thickness 0.15)
				)
			)
		)
		(property "Author" "Antmicro"
			(at 215.45 198.7 0)
			(layer "B.Fab")
			(hide yes)
			(effects
				(font
					(size 1 1)
					(thickness 0.15)
				)
				(justify mirror)
			)
		)
		(property "Dielectric" ""
			(at 215.45 198.7 0)
			(layer "B.Fab")
			(hide yes)
			(effects
				(font
					(size 1 1)
					(thickness 0.15)
				)
				(justify mirror)
			)
		)
		(property "License" "Apache-2.0"
			(at 215.45 198.7 0)
			(layer "B.Fab")
			(hide yes)
			(effects
				(font
					(size 1 1)
					(thickness 0.15)
				)
				(justify mirror)
			)
		)
		(property "MPN" "GRM155R61A475MEAAD"
			(at 215.45 198.7 0)
			(layer "B.Fab")
			(hide yes)
			(effects
				(font
					(size 1 1)
					(thickness 0.15)
				)
				(justify mirror)
			)
		)
		(property "Manufacturer" "Murata"
			(at 215.45 198.7 0)
			(layer "B.Fab")
			(hide yes)
			(effects
				(font
					(size 1 1)
					(thickness 0.15)
				)
				(justify mirror)
			)
		)
		(property "Val" "4u7"
			(at 215.45 198.7 0)
			(layer "B.Fab")
			(hide yes)
			(effects
				(font
					(size 1 1)
					(thickness 0.15)
				)
				(justify mirror)
			)
		)
		(property "Voltage" ""
			(at 215.45 198.7 0)
			(layer "B.Fab")
			(hide yes)
			(effects
				(font
					(size 1 1)
					(thickness 0.15)
				)
				(justify mirror)
			)
		)
		(sheetname "/Ethernet/")
		(sheetfile "ethernet.kicad_sch")
		(attr smd)
		(fp_rect
			(start -0.925 0.47)
			(end 0.925 -0.47)
			(stroke
				(width 0.05)
				(type default)
			)
			(fill no)
			(layer "B.CrtYd")
		)
		(fp_line
			(start 0.504 0.25)
			(end 0.504 -0.248)
			(stroke
				(width 0.15)
				(type solid)
			)
			(layer "B.Fab")
		)
		(fp_line
			(start 0.504 -0.248)
			(end -0.494 -0.248)
			(stroke
				(width 0.15)
				(type solid)
			)
			(layer "B.Fab")
		)
		(fp_line
			(start -0.494 0.25)
			(end 0.504 0.25)
			(stroke
				(width 0.15)
				(type solid)
			)
			(layer "B.Fab")
		)
		(fp_line
			(start -0.494 -0.248)
			(end -0.494 0.25)
			(stroke
				(width 0.15)
				(type solid)
			)
			(layer "B.Fab")
		)
		(pad "1" smd roundrect
			(at -0.48 0 180)
			(size 0.59 0.64)
			(layers "B.Cu" "B.Mask" "B.Paste")
			(roundrect_rratio 0.25)
			(net 1 "GND")
			(pintype "passive")
		)
		(pad "2" smd roundrect
			(at 0.48 0 180)
			(size 0.59 0.64)
			(layers "B.Cu" "B.Mask" "B.Paste")
			(roundrect_rratio 0.25)
			(net 339 "VCC1V2")
			(pintype "passive")
		)
	)
	(footprint "antmicro-footprints:R_0402_1005Metric"
		(layer "B.Cu")
		(at 77.975 147.175)
		(descr "Resistor SMD 0402")
		(tags "resistor SMD 0402")
		(property "Reference" "R133"
			(at -3.575 0.325 0)
			(layer "B.SilkS")
			(effects
				(font
					(size 0.7 0.7)
					(thickness 0.15)
				)
				(justify right bottom mirror)
			)
		)
		(property "Value" "R_2k2_0402"
			(at 0 -1.4 0)
			(layer "B.Fab")
			(effects
				(font
					(size 0.7 0.7)
					(thickness 0.15)
				)
				(justify right bottom mirror)
			)
		)
		(property "Datasheet" "https://www.bourns.com/docs/product-datasheets/cr.pdf"
			(at 0 0 0)
			(layer "F.Fab")
			(hide yes)
			(effects
				(font
					(size 1.27 1.27)
					(thickness 0.15)
				)
			)
		)
		(property "Description" "SMD Chip Resistor, 2.2 kohm, ± 1%, 62.5 mW, 0402 [1005 Metric], Thick Film, General Purpose"
			(at 0 0 0)
			(layer "F.Fab")
			(hide yes)
			(effects
				(font
					(size 1.27 1.27)
					(thickness 0.15)
				)
			)
		)
		(property "Author" "Antmicro"
			(at 0 0 0)
			(layer "B.Fab")
			(hide yes)
			(effects
				(font
					(size 1 1)
					(thickness 0.15)
				)
				(justify mirror)
			)
		)
		(property "License" "Apache-2.0"
			(at 0 0 0)
			(layer "B.Fab")
			(hide yes)
			(effects
				(font
					(size 1 1)
					(thickness 0.15)
				)
				(justify mirror)
			)
		)
		(property "MPN" "CR0402-FX-2201GLF"
			(at 0 0 0)
			(layer "B.Fab")
			(hide yes)
			(effects
				(font
					(size 1 1)
					(thickness 0.15)
				)
				(justify mirror)
			)
		)
		(property "Manufacturer" "Bourns"
			(at 0 0 0)
			(layer "B.Fab")
			(hide yes)
			(effects
				(font
					(size 1 1)
					(thickness 0.15)
				)
				(justify mirror)
			)
		)
		(property "Tolerance" "1%"
			(at 0 0 0)
			(layer "B.Fab")
			(hide yes)
			(effects
				(font
					(size 1 1)
					(thickness 0.15)
				)
				(justify mirror)
			)
		)
		(property "Val" "2k2"
			(at 0 0 0)
			(layer "B.Fab")
			(hide yes)
			(effects
				(font
					(size 1 1)
					(thickness 0.15)
				)
				(justify mirror)
			)
		)
		(property "DNP" ""
			(at 0 0 0)
			(unlocked yes)
			(layer "B.Fab")
			(hide yes)
			(effects
				(font
					(size 1 1)
					(thickness 0.15)
				)
				(justify mirror)
			)
		)
		(sheetname "/FPGA banks 13-16/")
		(sheetfile "fpga-banks-13-16.kicad_sch")
		(attr smd)
		(fp_rect
			(start -0.925 0.47)
			(end 0.925 -0.47)
			(stroke
				(width 0.05)
				(type default)
			)
			(fill no)
			(layer "B.CrtYd")
		)
		(fp_rect
			(start -0.5 0.25)
			(end 0.5 -0.25)
			(stroke
				(width 0.15)
				(type solid)
			)
			(fill no)
			(layer "B.Fab")
		)
		(pad "1" smd roundrect
			(at -0.48 0)
			(size 0.59 0.64)
			(layers "B.Cu" "B.Mask" "B.Paste")
			(roundrect_rratio 0.25)
			(net 2 "VCC3V3")
			(pintype "passive")
		)
		(pad "2" smd roundrect
			(at 0.48 0)
			(size 0.59 0.64)
			(layers "B.Cu" "B.Mask" "B.Paste")
			(roundrect_rratio 0.25)
			(net 344 "Net-(U14A-IO_L6P_T0_FCS_B_14)")
			(pintype "passive")
		)
	)
	(footprint "antmicro-footprints:R_0402_1005Metric"
		(layer "B.Cu")
		(at 71.195 135.315)
		(descr "Resistor SMD 0402")
		(tags "resistor SMD 0402")
		(property "Reference" "R31"
			(at -2.95 0.425 0)
			(layer "B.SilkS")
			(effects
				(font
					(size 0.7 0.7)
					(thickness 0.15)
				)
				(justify right bottom mirror)
			)
		)
		(property "Value" "R_10k_0402"
			(at 0 -1.4 0)
			(layer "B.Fab")
			(effects
				(font
					(size 0.7 0.7)
					(thickness 0.15)
				)
				(justify right bottom mirror)
			)
		)
		(property "Datasheet" "https://www.bourns.com/docs/product-datasheets/cr.pdf"
			(at 0 0 0)
			(layer "F.Fab")
			(hide yes)
			(effects
				(font
					(size 1.27 1.27)
					(thickness 0.15)
				)
			)
		)
		(property "Description" "SMD Chip Resistor, 10 kohm, ± 1%, 62.5 mW, 0402 [1005 Metric], Thick Film, General Purpose"
			(at 0 0 0)
			(layer "F.Fab")
			(hide yes)
			(effects
				(font
					(size 1.27 1.27)
					(thickness 0.15)
				)
			)
		)
		(property "Author" "Antmicro"
			(at 0 0 0)
			(layer "B.Fab")
			(hide yes)
			(effects
				(font
					(size 1 1)
					(thickness 0.15)
				)
				(justify mirror)
			)
		)
		(property "License" "Apache-2.0"
			(at 0 0 0)
			(layer "B.Fab")
			(hide yes)
			(effects
				(font
					(size 1 1)
					(thickness 0.15)
				)
				(justify mirror)
			)
		)
		(property "MPN" "CR0402-FX-1002GLF"
			(at 0 0 0)
			(layer "B.Fab")
			(hide yes)
			(effects
				(font
					(size 1 1)
					(thickness 0.15)
				)
				(justify mirror)
			)
		)
		(property "Manufacturer" "Bourns"
			(at 0 0 0)
			(layer "B.Fab")
			(hide yes)
			(effects
				(font
					(size 1 1)
					(thickness 0.15)
				)
				(justify mirror)
			)
		)
		(property "Tolerance" "1%"
			(at 0 0 0)
			(layer "B.Fab")
			(hide yes)
			(effects
				(font
					(size 1 1)
					(thickness 0.15)
				)
				(justify mirror)
			)
		)
		(property "Val" "10k"
			(at 0 0 0)
			(layer "B.Fab")
			(hide yes)
			(effects
				(font
					(size 1 1)
					(thickness 0.15)
				)
				(justify mirror)
			)
		)
		(sheetname "/RoT/")
		(sheetfile "rot.kicad_sch")
		(attr smd)
		(fp_rect
			(start -0.925 0.47)
			(end 0.925 -0.47)
			(stroke
				(width 0.05)
				(type default)
			)
			(fill no)
			(layer "B.CrtYd")
		)
		(fp_rect
			(start -0.5 0.25)
			(end 0.5 -0.25)
			(stroke
				(width 0.15)
				(type solid)
			)
			(fill no)
			(layer "B.Fab")
		)
		(pad "1" smd roundrect
			(at -0.48 0)
			(size 0.59 0.64)
			(layers "B.Cu" "B.Mask" "B.Paste")
			(roundrect_rratio 0.25)
			(net 136 "QSPIA2_D0")
			(pintype "passive")
		)
		(pad "2" smd roundrect
			(at 0.48 0)
			(size 0.59 0.64)
			(layers "B.Cu" "B.Mask" "B.Paste")
			(roundrect_rratio 0.25)
			(net 2 "VCC3V3")
			(pintype "passive")
		)
	)
	(footprint "antmicro-footprints:R_0402_1005Metric"
		(layer "B.Cu")
		(at 71.21 136.315 180)
		(descr "Resistor SMD 0402")
		(tags "resistor SMD 0402")
		(property "Reference" "R27"
			(at 0.81 -0.385 0)
			(layer "B.SilkS")
			(effects
				(font
					(size 0.7 0.7)
					(thickness 0.15)
				)
				(justify left bottom mirror)
			)
		)
		(property "Value" "R_1k_0402"
			(at 0 -1.4 0)
			(layer "B.Fab")
			(effects
				(font
					(size 0.7 0.7)
					(thickness 0.15)
				)
				(justify left bottom mirror)
			)
		)
		(property "Datasheet" "https://www.bourns.com/docs/product-datasheets/cr.pdf"
			(at 0 0 180)
			(layer "F.Fab")
			(hide yes)
			(effects
				(font
					(size 1.27 1.27)
					(thickness 0.15)
				)
			)
		)
		(property "Description" "SMD Chip Resistor, 1 kohm, ± 1%, 63 mW, 0402 [1005 Metric], Thick Film, General Purpose"
			(at 0 0 180)
			(layer "F.Fab")
			(hide yes)
			(effects
				(font
					(size 1.27 1.27)
					(thickness 0.15)
				)
			)
		)
		(property "Author" "Antmicro"
			(at 142.42 272.63 0)
			(layer "B.Fab")
			(hide yes)
			(effects
				(font
					(size 1 1)
					(thickness 0.15)
				)
				(justify mirror)
			)
		)
		(property "License" "Apache-2.0"
			(at 142.42 272.63 0)
			(layer "B.Fab")
			(hide yes)
			(effects
				(font
					(size 1 1)
					(thickness 0.15)
				)
				(justify mirror)
			)
		)
		(property "MPN" "CR0402-FX-1001GLF"
			(at 142.42 272.63 0)
			(layer "B.Fab")
			(hide yes)
			(effects
				(font
					(size 1 1)
					(thickness 0.15)
				)
				(justify mirror)
			)
		)
		(property "Manufacturer" "Bourns"
			(at 142.42 272.63 0)
			(layer "B.Fab")
			(hide yes)
			(effects
				(font
					(size 1 1)
					(thickness 0.15)
				)
				(justify mirror)
			)
		)
		(property "Tolerance" "1%"
			(at 142.42 272.63 0)
			(layer "B.Fab")
			(hide yes)
			(effects
				(font
					(size 1 1)
					(thickness 0.15)
				)
				(justify mirror)
			)
		)
		(property "Val" "1k"
			(at 142.42 272.63 0)
			(layer "B.Fab")
			(hide yes)
			(effects
				(font
					(size 1 1)
					(thickness 0.15)
				)
				(justify mirror)
			)
		)
		(sheetname "/RoT/")
		(sheetfile "rot.kicad_sch")
		(attr smd)
		(fp_rect
			(start -0.925 0.47)
			(end 0.925 -0.47)
			(stroke
				(width 0.05)
				(type default)
			)
			(fill no)
			(layer "B.CrtYd")
		)
		(fp_rect
			(start -0.5 0.25)
			(end 0.5 -0.25)
			(stroke
				(width 0.15)
				(type solid)
			)
			(fill no)
			(layer "B.Fab")
		)
		(pad "1" smd roundrect
			(at -0.48 0 180)
			(size 0.59 0.64)
			(layers "B.Cu" "B.Mask" "B.Paste")
			(roundrect_rratio 0.25)
			(net 2 "VCC3V3")
			(pintype "passive")
		)
		(pad "2" smd roundrect
			(at 0.48 0 180)
			(size 0.59 0.64)
			(layers "B.Cu" "B.Mask" "B.Paste")
			(roundrect_rratio 0.25)
			(net 130 "QSPIA_CLK")
			(pintype "passive")
		)
	)
	(footprint "antmicro-footprints:R_0402_1005Metric"
		(layer "B.Cu")
		(at 71.21 138.315 180)
		(descr "Resistor SMD 0402")
		(tags "resistor SMD 0402")
		(property "Reference" "R23"
			(at 0.81 -0.385 0)
			(layer "B.SilkS")
			(effects
				(font
					(size 0.7 0.7)
					(thickness 0.15)
				)
				(justify left bottom mirror)
			)
		)
		(property "Value" "R_4k7_0402"
			(at 0 -1.4 0)
			(layer "B.Fab")
			(effects
				(font
					(size 0.7 0.7)
					(thickness 0.15)
				)
				(justify left bottom mirror)
			)
		)
		(property "Datasheet" "https://www.bourns.com/docs/product-datasheets/cr.pdf"
			(at 0 0 180)
			(layer "F.Fab")
			(hide yes)
			(effects
				(font
					(size 1.27 1.27)
					(thickness 0.15)
				)
			)
		)
		(property "Description" "SMD Chip Resistor, 4.7 kohm, ± 1%, 62.5 mW, 0402 [1005 Metric], Thick Film, General Purpose"
			(at 0 0 180)
			(layer "F.Fab")
			(hide yes)
			(effects
				(font
					(size 1.27 1.27)
					(thickness 0.15)
				)
			)
		)
		(property "Author" "Antmicro"
			(at 142.42 276.63 0)
			(layer "B.Fab")
			(hide yes)
			(effects
				(font
					(size 1 1)
					(thickness 0.15)
				)
				(justify mirror)
			)
		)
		(property "License" "Apache-2.0"
			(at 142.42 276.63 0)
			(layer "B.Fab")
			(hide yes)
			(effects
				(font
					(size 1 1)
					(thickness 0.15)
				)
				(justify mirror)
			)
		)
		(property "MPN" "CR0402-FX-4701GLF"
			(at 142.42 276.63 0)
			(layer "B.Fab")
			(hide yes)
			(effects
				(font
					(size 1 1)
					(thickness 0.15)
				)
				(justify mirror)
			)
		)
		(property "Manufacturer" "Bourns"
			(at 142.42 276.63 0)
			(layer "B.Fab")
			(hide yes)
			(effects
				(font
					(size 1 1)
					(thickness 0.15)
				)
				(justify mirror)
			)
		)
		(property "Tolerance" "1%"
			(at 142.42 276.63 0)
			(layer "B.Fab")
			(hide yes)
			(effects
				(font
					(size 1 1)
					(thickness 0.15)
				)
				(justify mirror)
			)
		)
		(property "Val" "4k7"
			(at 142.42 276.63 0)
			(layer "B.Fab")
			(hide yes)
			(effects
				(font
					(size 1 1)
					(thickness 0.15)
				)
				(justify mirror)
			)
		)
		(sheetname "/RoT/")
		(sheetfile "rot.kicad_sch")
		(attr smd)
		(fp_rect
			(start -0.925 0.47)
			(end 0.925 -0.47)
			(stroke
				(width 0.05)
				(type default)
			)
			(fill no)
			(layer "B.CrtYd")
		)
		(fp_rect
			(start -0.5 0.25)
			(end 0.5 -0.25)
			(stroke
				(width 0.15)
				(type solid)
			)
			(fill no)
			(layer "B.Fab")
		)
		(pad "1" smd roundrect
			(at -0.48 0 180)
			(size 0.59 0.64)
			(layers "B.Cu" "B.Mask" "B.Paste")
			(roundrect_rratio 0.25)
			(net 2 "VCC3V3")
			(pintype "passive")
		)
		(pad "2" smd roundrect
			(at 0.48 0 180)
			(size 0.59 0.64)
			(layers "B.Cu" "B.Mask" "B.Paste")
			(roundrect_rratio 0.25)
			(net 140 "QSPIA2_CS_N")
			(pintype "passive")
		)
	)
)
